# TIMECARD (Time Appliance Project (Time Card)) — schematic netlist excerpt (pin names and nets, part order shuffled) for the footprints in the layout excerpt that follows; sources: Cadence DE-HDL packaged netlist, KiCad conversion of R4006-B0001-02_R01.brd

C290  CAPACITOR  0.1UF 25V 10%  pkg SMC_0402R_H022  page 9 : \1\ = XP3R3V_PCIE ; \2\ = SG
R58  RESISTOR  33OHM 1%  pkg SMC_0402R_H016  page 16 : \1\ = UNNAMED_5_CONNHDR2X2MSSMT_I126_ ; \2\ = R_PCA9546_I2C_SDA

(kicad_pcb
	(version 20260206)
	(generator "pcbnew")
	(generator_version "10.0")
	(general
		(thickness 1.6)
		(legacy_teardrops no)
	)
	(paper "A4")
	(title_block
		(title "timecard-production-celestica-r4006 — R4006-B0001-02_R01.brd")
		(comment 1 "Time Appliance Project (Time Card) / footprints 817-818 of 1113")
	)
	(layers
		(0 "F.Cu" signal "TOP")
		(4 "In1.Cu" signal "L02_GND1")
		(6 "In2.Cu" signal "L03_SIG1")
		(8 "In3.Cu" signal "L04_GND2")
		(10 "In4.Cu" signal "L05_VCC1")
		(12 "In5.Cu" signal "L06_VCC2")
		(14 "In6.Cu" signal "L07_GND3")
		(16 "In7.Cu" signal "L08_SIG2")
		(18 "In8.Cu" signal "L09_GND4")
		(2 "B.Cu" signal "BOTTOM")
		(9 "F.Adhes" user "F.Adhesive")
		(11 "B.Adhes" user "B.Adhesive")
		(13 "F.Paste" user "Package Geometry/Pastemask Top")
		(15 "B.Paste" user "Package Geometry/Pastemask Bottom")
		(5 "F.SilkS" user "Ref Des/Silkscreen Top")
		(7 "B.SilkS" user "Ref Des/Silkscreen Bottom")
		(1 "F.Mask" user "Board Geometry/Soldermask Top")
		(3 "B.Mask" user "Board Geometry/Soldermask Bottom")
		(17 "Dwgs.User" user "User.Drawings")
		(19 "Cmts.User" user "User.Comments")
		(21 "Eco1.User" user "User.Eco1")
		(23 "Eco2.User" user "User.Eco2")
		(25 "Edge.Cuts" user "Board Geometry/Outline")
		(27 "Margin" user)
		(31 "F.CrtYd" user "Package Geometry/Place Bound Top")
		(29 "B.CrtYd" user "Package Geometry/Place Bound Bottom")
		(35 "F.Fab" user "Ref Des/Assembly Top")
		(33 "B.Fab" user "Ref Des/Assembly Bottom")
	)
	(footprint ""
		(layer "B.Cu")
		(at 55.88 -16.129 -90)
		(property "Reference" "C290"
			(at -4.064 -0.59563 270)
			(unlocked yes)
			(layer "B.SilkS")
			(effects
				(font
					(size 0.7874 0.5842)
					(thickness 0.1524)
				)
				(justify mirror)
			)
		)
		(property "Value" "VAL*"
			(at -0.0762 2.067306 270)
			(unlocked yes)
			(layer "B.Fab")
			(hide yes)
			(effects
				(font
					(size 0.7874 0.5842)
					(thickness 0.1524)
				)
				(justify mirror)
			)
		)
		(property "Device Type" "CAPACITOR-G105-0B104-EK,0.1UF,A"
			(at -0.0508 1.127506 270)
			(unlocked yes)
			(layer "B.Fab")
			(hide yes)
			(effects
				(font
					(size 0.7874 0.5842)
					(thickness 0.1524)
				)
				(justify mirror)
			)
		)
		(property "User Part Number" "PARTNUM*"
			(at -0.1016 4.023106 270)
			(unlocked yes)
			(layer "Cmts.User")
			(hide yes)
			(effects
				(font
					(size 0.7874 0.5842)
					(thickness 0.1524)
				)
				(justify mirror)
			)
		)
		(property "Tolerance" "TOL*"
			(at -0.0762 3.032506 270)
			(unlocked yes)
			(layer "Cmts.User")
			(hide yes)
			(effects
				(font
					(size 0.7874 0.5842)
					(thickness 0.1524)
				)
				(justify mirror)
			)
		)
		(duplicate_pad_numbers_are_jumpers no)
		(fp_line
			(start -1.143 0.5588)
			(end -1.143 -0.5588)
			(stroke
				(width 0.1)
				(type default)
			)
			(layer "B.SilkS")
		)
		(fp_line
			(start 1.143 0.5588)
			(end -1.143 0.5588)
			(stroke
				(width 0.1)
				(type default)
			)
			(layer "B.SilkS")
		)
		(fp_line
			(start -1.143 -0.5588)
			(end 1.143 -0.5588)
			(stroke
				(width 0.1)
				(type default)
			)
			(layer "B.SilkS")
		)
		(fp_line
			(start 1.143 -0.5588)
			(end 1.143 0.5588)
			(stroke
				(width 0.1)
				(type default)
			)
			(layer "B.SilkS")
		)
		(fp_poly
			(pts
				(xy 1.143 0.5588) (xy -1.143 0.5588) (xy -1.143 -0.5588) (xy 1.143 -0.5588)
			)
			(stroke
				(width 0)
				(type default)
			)
			(fill no)
			(layer "B.CrtYd")
		)
		(fp_line
			(start -0.508 0.3048)
			(end -0.508 -0.3048)
			(stroke
				(width 0.1)
				(type default)
			)
			(layer "B.Fab")
		)
		(fp_line
			(start 0.508 0.3048)
			(end -0.508 0.3048)
			(stroke
				(width 0.1)
				(type default)
			)
			(layer "B.Fab")
		)
		(fp_line
			(start -0.508 -0.3048)
			(end 0.508 -0.3048)
			(stroke
				(width 0.1)
				(type default)
			)
			(layer "B.Fab")
		)
		(fp_line
			(start 0.508 -0.3048)
			(end 0.508 0.3048)
			(stroke
				(width 0.1)
				(type default)
			)
			(layer "B.Fab")
		)
		(pad "1" smd rect
			(at 0.5334 0 90)
			(size 0.7112 0.6096)
			(layers "B.Cu" "B.Mask" "B.Paste")
			(net "XP3R3V_PCIE")
		)
		(pad "2" smd rect
			(at -0.5334 0 90)
			(size 0.7112 0.6096)
			(layers "B.Cu" "B.Mask" "B.Paste")
			(net "SG")
		)
		(zone
			(layer "B.Cu")
			(hatch none 0.5)
			(connect_pads
				(clearance 0)
			)
			(min_thickness 0.25)
			(keepout
				(tracks allowed)
				(vias not_allowed)
				(pads allowed)
				(copperpour not_allowed)
				(footprints allowed)
			)
			(placement
				(enabled no)
				(sheetname "")
			)
			(fill
				(thermal_gap 0.5)
				(thermal_bridge_width 0.5)
				(island_removal_mode 0)
			)
			(polygon
				(pts
					(xy 55.5752 -16.0528) (xy 56.1848 -16.0528) (xy 56.1848 -16.2052) (xy 55.5752 -16.2052)
				)
			)
		)
		(zone
			(layer "B.Cu")
			(hatch none 0.5)
			(connect_pads
				(clearance 0)
			)
			(min_thickness 0.25)
			(keepout
				(tracks not_allowed)
				(vias allowed)
				(pads allowed)
				(copperpour not_allowed)
				(footprints allowed)
			)
			(placement
				(enabled no)
				(sheetname "")
			)
			(fill
				(thermal_gap 0.5)
				(thermal_bridge_width 0.5)
				(island_removal_mode 0)
			)
			(polygon
				(pts
					(xy 55.5752 -16.0528) (xy 56.1848 -16.0528) (xy 56.1848 -16.2052) (xy 55.5752 -16.2052)
				)
			)
		)
	)
	(footprint ""
		(layer "B.Cu")
		(at 21.0566 -42.7736)
		(property "Reference" "R58"
			(at -1.3716 -1.25603 0)
			(unlocked yes)
			(layer "B.SilkS")
			(effects
				(font
					(size 0.7874 0.5842)
					(thickness 0.1524)
				)
				(justify mirror)
			)
		)
		(property "Value" "VAL*"
			(at -0.02032 2.13233 0)
			(unlocked yes)
			(layer "B.Fab")
			(hide yes)
			(effects
				(font
					(size 0.7874 0.5842)
					(thickness 0.1524)
				)
				(justify mirror)
			)
		)
		(property "Device Type" "RESISTOR-G155-133R0-01,33OHM,1%"
			(at -0.008382 1.210564 0)
			(unlocked yes)
			(layer "B.Fab")
			(hide yes)
			(effects
				(font
					(size 0.7874 0.5842)
					(thickness 0.1524)
				)
				(justify mirror)
			)
		)
		(property "User Part Number" "PARTNUM*"
			(at -0.02032 4.024884 0)
			(unlocked yes)
			(layer "Cmts.User")
			(hide yes)
			(effects
				(font
					(size 0.7874 0.5842)
					(thickness 0.1524)
				)
				(justify mirror)
			)
		)
		(property "Tolerance" "TOL*"
			(at -0.044704 3.05435 0)
			(unlocked yes)
			(layer "Cmts.User")
			(hide yes)
			(effects
				(font
					(size 0.7874 0.5842)
					(thickness 0.1524)
				)
				(justify mirror)
			)
		)
		(duplicate_pad_numbers_are_jumpers no)
		(fp_line
			(start -1.143 -0.5588)
			(end 1.143 -0.5588)
			(stroke
				(width 0.1)
				(type default)
			)
			(layer "B.SilkS")
		)
		(fp_line
			(start -1.143 0.5588)
			(end -1.143 -0.5588)
			(stroke
				(width 0.1)
				(type default)
			)
			(layer "B.SilkS")
		)
		(fp_line
			(start 1.143 -0.5588)
			(end 1.143 0.5588)
			(stroke
				(width 0.1)
				(type default)
			)
			(layer "B.SilkS")
		)
		(fp_line
			(start 1.143 0.5588)
			(end -1.143 0.5588)
			(stroke
				(width 0.1)
				(type default)
			)
			(layer "B.SilkS")
		)
		(fp_rect
			(start 1.143 0.5588)
			(end -1.143 -0.5588)
			(stroke
				(width 0)
				(type default)
			)
			(fill no)
			(layer "B.CrtYd")
		)
		(fp_line
			(start -0.508 -0.3048)
			(end 0.508 -0.3048)
			(stroke
				(width 0.1)
				(type default)
			)
			(layer "B.Fab")
		)
		(fp_line
			(start -0.508 0.3048)
			(end -0.508 -0.3048)
			(stroke
				(width 0.1)
				(type default)
			)
			(layer "B.Fab")
		)
		(fp_line
			(start 0.508 -0.3048)
			(end 0.508 0.3048)
			(stroke
				(width 0.1)
				(type default)
			)
			(layer "B.Fab")
		)
		(fp_line
			(start 0.508 0.3048)
			(end -0.508 0.3048)
			(stroke
				(width 0.1)
				(type default)
			)
			(layer "B.Fab")
		)
		(pad "1" smd rect
			(at 0.5334 0 180)
			(size 0.7112 0.6096)
			(layers "B.Cu" "B.Mask" "B.Paste")
			(net "UNNAMED_5_CONNHDR2X2MSSMT_I126_")
		)
		(pad "2" smd rect
			(at -0.5334 0 180)
			(size 0.7112 0.6096)
			(layers "B.Cu" "B.Mask" "B.Paste")
			(net "R_PCA9546_I2C_SDA")
		)
		(zone
			(layer "B.Cu")
			(hatch none 0.5)
			(connect_pads
				(clearance 0)
			)
			(min_thickness 0.25)
			(keepout
				(tracks allowed)
				(vias not_allowed)
				(pads allowed)
				(copperpour not_allowed)
				(footprints allowed)
			)
			(placement
				(enabled no)
				(sheetname "")
			)
			(fill
				(thermal_gap 0.5)
				(thermal_bridge_width 0.5)
				(island_removal_mode 0)
			)
			(polygon
				(pts
					(xy 21.1328 -42.4688) (xy 21.1328 -43.0784) (xy 20.9804 -43.0784) (xy 20.9804 -42.4688)
				)
			)
		)
	)
)
